# T6G (Grand Teton) — schematic netlist excerpt (pin names and nets, part order shuffled) for the footprints in the layout excerpt that follows; sources: Cadence DE-HDL packaged netlist, KiCad conversion of 04192023_DAF0TMB3IC0_F0TG_MB_C_brd_V02_OCP.brd

R1423  Q_RES  0 5% CHIP  pkg 0402LF  page 164 : A = UART_CPU0_SCM_UART1_RX ; B = UART_CPU0_SCM_UART1_R_RX
C1340  Q_CAP  10UF 16V 10% X6S  pkg C0805  page 188 : A = P3V3 ; B = GND
PC639  Q_CAP  3300PF 50V 10% X7R  pkg 0402  page 224 : A = VSENSE_PVDD11_S3_P1_R ; B = VSENSE_VSS_SENSE_C_P1

(kicad_pcb
	(version 20260206)
	(generator "pcbnew")
	(generator_version "10.0")
	(general
		(thickness 1.6)
		(legacy_teardrops no)
	)
	(paper "A4")
	(title_block
		(title "04192023_DAF0TMB3IC0_F0TG_MB_C_brd_V02_OCP.brd")
		(comment 1 "Grand Teton / footprints 386-388 of 8354")
	)
	(layers
		(0 "F.Cu" signal "TOP")
		(4 "In1.Cu" signal "GND")
		(6 "In2.Cu" signal "IN1")
		(8 "In3.Cu" signal "GND1")
		(10 "In4.Cu" signal "IN2")
		(12 "In5.Cu" signal "GND2")
		(14 "In6.Cu" signal "IN3")
		(16 "In7.Cu" signal "GND3")
		(18 "In8.Cu" signal "VCC")
		(20 "In9.Cu" signal "VCC1")
		(22 "In10.Cu" signal "GND4")
		(24 "In11.Cu" signal "IN4")
		(26 "In12.Cu" signal "GND5")
		(28 "In13.Cu" signal "IN5")
		(30 "In14.Cu" signal "GND6")
		(32 "In15.Cu" signal "IN6")
		(34 "In16.Cu" signal "GND7")
		(2 "B.Cu" signal "BOTTOM")
		(9 "F.Adhes" user "F.Adhesive")
		(11 "B.Adhes" user "B.Adhesive")
		(13 "F.Paste" user "Package Geometry/Pastemask Top")
		(15 "B.Paste" user "Package Geometry/Pastemask Bottom")
		(5 "F.SilkS" user "Ref Des/Silkscreen Top")
		(7 "B.SilkS" user "Ref Des/Silkscreen Bottom")
		(1 "F.Mask" user "Board Geometry/Soldermask Top")
		(3 "B.Mask" user "Board Geometry/Soldermask Bottom")
		(17 "Dwgs.User" user "User.Drawings")
		(19 "Cmts.User" user "User.Comments")
		(21 "Eco1.User" user "User.Eco1")
		(23 "Eco2.User" user "User.Eco2")
		(25 "Edge.Cuts" user "Board Geometry/Outline")
		(27 "Margin" user)
		(31 "F.CrtYd" user "Package Geometry/Place Bound Top")
		(29 "B.CrtYd" user "Package Geometry/Place Bound Bottom")
		(35 "F.Fab" user "Ref Des/Assembly Top")
		(33 "B.Fab" user "Ref Des/Assembly Bottom")
	)
	(footprint ""
		(layer "F.Cu")
		(at 368.241326 -43.235118 -90)
		(property "Reference" "R1423"
			(at 0 0 270)
			(layer "F.SilkS")
			(hide yes)
			(effects
				(font
					(size 1.27 1.27)
				)
			)
		)
		(property "Value" ""
			(at 0 0 270)
			(layer "F.Fab")
			(effects
				(font
					(size 1.27 1.27)
				)
			)
		)
		(duplicate_pad_numbers_are_jumpers no)
		(fp_line
			(start -0.7874 0.4064)
			(end -0.7874 -0.4064)
			(stroke
				(width 0.1524)
				(type default)
			)
			(layer "F.SilkS")
		)
		(fp_line
			(start 0.7874 0.4064)
			(end -0.7874 0.4064)
			(stroke
				(width 0.1524)
				(type default)
			)
			(layer "F.SilkS")
		)
		(fp_line
			(start -0.7874 -0.4064)
			(end 0.7874 -0.4064)
			(stroke
				(width 0.1524)
				(type default)
			)
			(layer "F.SilkS")
		)
		(fp_line
			(start 0.7874 -0.4064)
			(end 0.7874 0.4064)
			(stroke
				(width 0.1524)
				(type default)
			)
			(layer "F.SilkS")
		)
		(fp_line
			(start -0.67945 0.3048)
			(end -0.67945 -0.305054)
			(stroke
				(width 0.1)
				(type default)
			)
			(layer "F.Fab")
		)
		(fp_line
			(start -0.12065 0.3048)
			(end -0.67945 0.3048)
			(stroke
				(width 0.1)
				(type default)
			)
			(layer "F.Fab")
		)
		(fp_line
			(start 0.120396 0.3048)
			(end 0.120396 0.2794)
			(stroke
				(width 0.1)
				(type default)
			)
			(layer "F.Fab")
		)
		(fp_line
			(start 0.67945 0.3048)
			(end 0.120396 0.3048)
			(stroke
				(width 0.1)
				(type default)
			)
			(layer "F.Fab")
		)
		(fp_line
			(start -0.12065 0.2794)
			(end -0.12065 0.3048)
			(stroke
				(width 0.1)
				(type default)
			)
			(layer "F.Fab")
		)
		(fp_line
			(start 0.120396 0.2794)
			(end -0.12065 0.2794)
			(stroke
				(width 0.1)
				(type default)
			)
			(layer "F.Fab")
		)
		(fp_line
			(start -0.12065 -0.2794)
			(end 0.12065 -0.2794)
			(stroke
				(width 0.1)
				(type default)
			)
			(layer "F.Fab")
		)
		(fp_line
			(start 0.12065 -0.2794)
			(end 0.12065 -0.3048)
			(stroke
				(width 0.1)
				(type default)
			)
			(layer "F.Fab")
		)
		(fp_line
			(start 0.12065 -0.3048)
			(end 0.67945 -0.3048)
			(stroke
				(width 0.1)
				(type default)
			)
			(layer "F.Fab")
		)
		(fp_line
			(start 0.67945 -0.3048)
			(end 0.67945 0.3048)
			(stroke
				(width 0.1)
				(type default)
			)
			(layer "F.Fab")
		)
		(fp_line
			(start -0.67945 -0.305054)
			(end -0.12065 -0.305054)
			(stroke
				(width 0.1)
				(type default)
			)
			(layer "F.Fab")
		)
		(fp_line
			(start -0.12065 -0.305054)
			(end -0.12065 -0.2794)
			(stroke
				(width 0.1)
				(type default)
			)
			(layer "F.Fab")
		)
		(pad "1" smd circle
			(at -0.40005 0 270)
			(size 0 0)
			(layers "F.Cu" "F.Mask" "F.Paste")
			(net "UART_CPU0_SCM_UART1_RX")
		)
		(pad "2" smd circle
			(at 0.40005 0 270)
			(size 0 0)
			(layers "F.Cu" "F.Mask" "F.Paste")
			(net "UART_CPU0_SCM_UART1_R_RX")
		)
	)
	(footprint ""
		(layer "F.Cu")
		(at 159.741108 -344.706956)
		(property "Reference" "PC639"
			(at 0 0 0)
			(layer "F.SilkS")
			(hide yes)
			(effects
				(font
					(size 1.27 1.27)
				)
			)
		)
		(property "Value" ""
			(at 0 0 0)
			(layer "F.Fab")
			(effects
				(font
					(size 1.27 1.27)
				)
			)
		)
		(duplicate_pad_numbers_are_jumpers no)
		(fp_line
			(start -0.7874 -0.4064)
			(end 0.7874 -0.4064)
			(stroke
				(width 0.1524)
				(type default)
			)
			(layer "F.SilkS")
		)
		(fp_line
			(start -0.7874 0.4064)
			(end -0.7874 -0.4064)
			(stroke
				(width 0.1524)
				(type default)
			)
			(layer "F.SilkS")
		)
		(fp_line
			(start 0.7874 -0.4064)
			(end 0.7874 0.4064)
			(stroke
				(width 0.1524)
				(type default)
			)
			(layer "F.SilkS")
		)
		(fp_line
			(start 0.7874 0.4064)
			(end -0.7874 0.4064)
			(stroke
				(width 0.1524)
				(type default)
			)
			(layer "F.SilkS")
		)
		(fp_line
			(start -0.67945 -0.305054)
			(end -0.12065 -0.305054)
			(stroke
				(width 0.1)
				(type default)
			)
			(layer "F.Fab")
		)
		(fp_line
			(start -0.67945 0.3048)
			(end -0.67945 -0.305054)
			(stroke
				(width 0.1)
				(type default)
			)
			(layer "F.Fab")
		)
		(fp_line
			(start -0.12065 -0.305054)
			(end -0.12065 -0.2794)
			(stroke
				(width 0.1)
				(type default)
			)
			(layer "F.Fab")
		)
		(fp_line
			(start -0.12065 -0.2794)
			(end 0.12065 -0.2794)
			(stroke
				(width 0.1)
				(type default)
			)
			(layer "F.Fab")
		)
		(fp_line
			(start -0.12065 0.2794)
			(end -0.12065 0.3048)
			(stroke
				(width 0.1)
				(type default)
			)
			(layer "F.Fab")
		)
		(fp_line
			(start -0.12065 0.3048)
			(end -0.67945 0.3048)
			(stroke
				(width 0.1)
				(type default)
			)
			(layer "F.Fab")
		)
		(fp_line
			(start 0.120396 0.2794)
			(end -0.12065 0.2794)
			(stroke
				(width 0.1)
				(type default)
			)
			(layer "F.Fab")
		)
		(fp_line
			(start 0.120396 0.3048)
			(end 0.120396 0.2794)
			(stroke
				(width 0.1)
				(type default)
			)
			(layer "F.Fab")
		)
		(fp_line
			(start 0.12065 -0.3048)
			(end 0.67945 -0.3048)
			(stroke
				(width 0.1)
				(type default)
			)
			(layer "F.Fab")
		)
		(fp_line
			(start 0.12065 -0.2794)
			(end 0.12065 -0.3048)
			(stroke
				(width 0.1)
				(type default)
			)
			(layer "F.Fab")
		)
		(fp_line
			(start 0.67945 -0.3048)
			(end 0.67945 0.3048)
			(stroke
				(width 0.1)
				(type default)
			)
			(layer "F.Fab")
		)
		(fp_line
			(start 0.67945 0.3048)
			(end 0.120396 0.3048)
			(stroke
				(width 0.1)
				(type default)
			)
			(layer "F.Fab")
		)
		(pad "1" smd circle
			(at -0.40005 0)
			(size 0 0)
			(layers "F.Cu" "F.Mask" "F.Paste")
			(net "VSENSE_PVDD11_S3_P1_R")
		)
		(pad "2" smd circle
			(at 0.40005 0)
			(size 0 0)
			(layers "F.Cu" "F.Mask" "F.Paste")
			(net "VSENSE_VSS_SENSE_C_P1")
		)
	)
	(footprint ""
		(layer "F.Cu")
		(at 444.136018 -76.107798)
		(property "Reference" "C1340"
			(at 0 0 0)
			(layer "F.SilkS")
			(hide yes)
			(effects
				(font
					(size 1.27 1.27)
				)
			)
		)
		(property "Value" ""
			(at 0 0 0)
			(layer "F.Fab")
			(effects
				(font
					(size 1.27 1.27)
				)
			)
		)
		(duplicate_pad_numbers_are_jumpers no)
		(fp_line
			(start -1.524 -0.762)
			(end 1.524 -0.762)
			(stroke
				(width 0.1524)
				(type default)
			)
			(layer "F.SilkS")
		)
		(fp_line
			(start -1.524 0.762)
			(end -1.524 -0.762)
			(stroke
				(width 0.1524)
				(type default)
			)
			(layer "F.SilkS")
		)
		(fp_line
			(start 1.524 -0.762)
			(end 1.524 0.762)
			(stroke
				(width 0.1524)
				(type default)
			)
			(layer "F.SilkS")
		)
		(fp_line
			(start 1.524 0.762)
			(end -1.524 0.762)
			(stroke
				(width 0.1524)
				(type default)
			)
			(layer "F.SilkS")
		)
		(fp_line
			(start -1.1049 -0.724916)
			(end -1.1049 0.724916)
			(stroke
				(width 0.1)
				(type default)
			)
			(layer "F.Fab")
		)
		(fp_line
			(start -1.1049 0.724916)
			(end 1.1049 0.724916)
			(stroke
				(width 0.1)
				(type default)
			)
			(layer "F.Fab")
		)
		(fp_line
			(start 1.1049 -0.724916)
			(end -1.1049 -0.724916)
			(stroke
				(width 0.1)
				(type default)
			)
			(layer "F.Fab")
		)
		(fp_line
			(start 1.1049 0.724916)
			(end 1.1049 -0.724916)
			(stroke
				(width 0.1)
				(type default)
			)
			(layer "F.Fab")
		)
		(pad "1" smd rect
			(at -0.889 0 180)
			(size 1.016 1.27)
			(layers "F.Cu" "F.Mask" "F.Paste")
			(net "P3V3")
		)
		(pad "2" smd rect
			(at 0.889 0 180)
			(size 1.016 1.27)
			(layers "F.Cu" "F.Mask" "F.Paste")
			(net "GND")
		)
	)
)
